# T6G (Grand Teton) — schematic netlist excerpt (pin names and nets, part order shuffled) for the footprints in the layout excerpt that follows; sources: Cadence DE-HDL packaged netlist, KiCad conversion of 04192023_DAF0TMB3IC0_F0TG_MB_C_brd_V02_OCP.brd

R6165  Q_RES  1K 1% EMPTY  pkg 0402LF  page 112 : A = P3V3_AUX ; B = FM_P2E_BUF2_EQB0
R1532  Q_RES  1K 1% EMPTY  pkg 0402LF  page 77 : A = PVDD18_S5_P0 ; B = SPI_CPU0_D0

(kicad_pcb
	(version 20260206)
	(generator "pcbnew")
	(generator_version "10.0")
	(general
		(thickness 1.6)
		(legacy_teardrops no)
	)
	(paper "A4")
	(title_block
		(title "04192023_DAF0TMB3IC0_F0TG_MB_C_brd_V02_OCP.brd")
		(comment 1 "Grand Teton / footprints 1826-1827 of 8354")
	)
	(layers
		(0 "F.Cu" signal "TOP")
		(4 "In1.Cu" signal "GND")
		(6 "In2.Cu" signal "IN1")
		(8 "In3.Cu" signal "GND1")
		(10 "In4.Cu" signal "IN2")
		(12 "In5.Cu" signal "GND2")
		(14 "In6.Cu" signal "IN3")
		(16 "In7.Cu" signal "GND3")
		(18 "In8.Cu" signal "VCC")
		(20 "In9.Cu" signal "VCC1")
		(22 "In10.Cu" signal "GND4")
		(24 "In11.Cu" signal "IN4")
		(26 "In12.Cu" signal "GND5")
		(28 "In13.Cu" signal "IN5")
		(30 "In14.Cu" signal "GND6")
		(32 "In15.Cu" signal "IN6")
		(34 "In16.Cu" signal "GND7")
		(2 "B.Cu" signal "BOTTOM")
		(9 "F.Adhes" user "F.Adhesive")
		(11 "B.Adhes" user "B.Adhesive")
		(13 "F.Paste" user "Package Geometry/Pastemask Top")
		(15 "B.Paste" user "Package Geometry/Pastemask Bottom")
		(5 "F.SilkS" user "Ref Des/Silkscreen Top")
		(7 "B.SilkS" user "Ref Des/Silkscreen Bottom")
		(1 "F.Mask" user "Board Geometry/Soldermask Top")
		(3 "B.Mask" user "Board Geometry/Soldermask Bottom")
		(17 "Dwgs.User" user "User.Drawings")
		(19 "Cmts.User" user "User.Comments")
		(21 "Eco1.User" user "User.Eco1")
		(23 "Eco2.User" user "User.Eco2")
		(25 "Edge.Cuts" user "Board Geometry/Outline")
		(27 "Margin" user)
		(31 "F.CrtYd" user "Package Geometry/Place Bound Top")
		(29 "B.CrtYd" user "Package Geometry/Place Bound Bottom")
		(35 "F.Fab" user "Ref Des/Assembly Top")
		(33 "B.Fab" user "Ref Des/Assembly Bottom")
	)
	(footprint ""
		(layer "F.Cu")
		(at 22.892258 -427.580298 -90)
		(property "Reference" "R6165"
			(at 0 0 270)
			(layer "F.SilkS")
			(hide yes)
			(effects
				(font
					(size 1.27 1.27)
				)
			)
		)
		(property "Value" ""
			(at 0 0 270)
			(layer "F.Fab")
			(effects
				(font
					(size 1.27 1.27)
				)
			)
		)
		(duplicate_pad_numbers_are_jumpers no)
		(fp_line
			(start -0.7874 0.4064)
			(end -0.7874 -0.4064)
			(stroke
				(width 0.1524)
				(type default)
			)
			(layer "F.SilkS")
		)
		(fp_line
			(start 0.7874 0.4064)
			(end -0.7874 0.4064)
			(stroke
				(width 0.1524)
				(type default)
			)
			(layer "F.SilkS")
		)
		(fp_line
			(start -0.7874 -0.4064)
			(end 0.7874 -0.4064)
			(stroke
				(width 0.1524)
				(type default)
			)
			(layer "F.SilkS")
		)
		(fp_line
			(start 0.7874 -0.4064)
			(end 0.7874 0.4064)
			(stroke
				(width 0.1524)
				(type default)
			)
			(layer "F.SilkS")
		)
		(fp_line
			(start -0.67945 0.3048)
			(end -0.67945 -0.305054)
			(stroke
				(width 0.1)
				(type default)
			)
			(layer "F.Fab")
		)
		(fp_line
			(start -0.12065 0.3048)
			(end -0.67945 0.3048)
			(stroke
				(width 0.1)
				(type default)
			)
			(layer "F.Fab")
		)
		(fp_line
			(start 0.120396 0.3048)
			(end 0.120396 0.2794)
			(stroke
				(width 0.1)
				(type default)
			)
			(layer "F.Fab")
		)
		(fp_line
			(start 0.67945 0.3048)
			(end 0.120396 0.3048)
			(stroke
				(width 0.1)
				(type default)
			)
			(layer "F.Fab")
		)
		(fp_line
			(start -0.12065 0.2794)
			(end -0.12065 0.3048)
			(stroke
				(width 0.1)
				(type default)
			)
			(layer "F.Fab")
		)
		(fp_line
			(start 0.120396 0.2794)
			(end -0.12065 0.2794)
			(stroke
				(width 0.1)
				(type default)
			)
			(layer "F.Fab")
		)
		(fp_line
			(start -0.12065 -0.2794)
			(end 0.12065 -0.2794)
			(stroke
				(width 0.1)
				(type default)
			)
			(layer "F.Fab")
		)
		(fp_line
			(start 0.12065 -0.2794)
			(end 0.12065 -0.3048)
			(stroke
				(width 0.1)
				(type default)
			)
			(layer "F.Fab")
		)
		(fp_line
			(start 0.12065 -0.3048)
			(end 0.67945 -0.3048)
			(stroke
				(width 0.1)
				(type default)
			)
			(layer "F.Fab")
		)
		(fp_line
			(start 0.67945 -0.3048)
			(end 0.67945 0.3048)
			(stroke
				(width 0.1)
				(type default)
			)
			(layer "F.Fab")
		)
		(fp_line
			(start -0.67945 -0.305054)
			(end -0.12065 -0.305054)
			(stroke
				(width 0.1)
				(type default)
			)
			(layer "F.Fab")
		)
		(fp_line
			(start -0.12065 -0.305054)
			(end -0.12065 -0.2794)
			(stroke
				(width 0.1)
				(type default)
			)
			(layer "F.Fab")
		)
		(pad "1" smd circle
			(at -0.40005 0 270)
			(size 0 0)
			(layers "F.Cu" "F.Mask" "F.Paste")
			(net "P3V3_AUX")
		)
		(pad "2" smd circle
			(at 0.40005 0 270)
			(size 0 0)
			(layers "F.Cu" "F.Mask" "F.Paste")
			(net "FM_P2E_BUF2_EQB0")
		)
	)
	(footprint ""
		(layer "F.Cu")
		(at 263.906 -141.986 90)
		(property "Reference" "R1532"
			(at 0 0 90)
			(layer "F.SilkS")
			(hide yes)
			(effects
				(font
					(size 1.27 1.27)
				)
			)
		)
		(property "Value" ""
			(at 0 0 90)
			(layer "F.Fab")
			(effects
				(font
					(size 1.27 1.27)
				)
			)
		)
		(duplicate_pad_numbers_are_jumpers no)
		(fp_line
			(start 0.7874 -0.4064)
			(end 0.7874 0.4064)
			(stroke
				(width 0.1524)
				(type default)
			)
			(layer "F.SilkS")
		)
		(fp_line
			(start -0.7874 -0.4064)
			(end 0.7874 -0.4064)
			(stroke
				(width 0.1524)
				(type default)
			)
			(layer "F.SilkS")
		)
		(fp_line
			(start 0.7874 0.4064)
			(end -0.7874 0.4064)
			(stroke
				(width 0.1524)
				(type default)
			)
			(layer "F.SilkS")
		)
		(fp_line
			(start -0.7874 0.4064)
			(end -0.7874 -0.4064)
			(stroke
				(width 0.1524)
				(type default)
			)
			(layer "F.SilkS")
		)
		(fp_line
			(start -0.12065 -0.305054)
			(end -0.12065 -0.2794)
			(stroke
				(width 0.1)
				(type default)
			)
			(layer "F.Fab")
		)
		(fp_line
			(start -0.67945 -0.305054)
			(end -0.12065 -0.305054)
			(stroke
				(width 0.1)
				(type default)
			)
			(layer "F.Fab")
		)
		(fp_line
			(start 0.67945 -0.3048)
			(end 0.67945 0.3048)
			(stroke
				(width 0.1)
				(type default)
			)
			(layer "F.Fab")
		)
		(fp_line
			(start 0.12065 -0.3048)
			(end 0.67945 -0.3048)
			(stroke
				(width 0.1)
				(type default)
			)
			(layer "F.Fab")
		)
		(fp_line
			(start 0.12065 -0.2794)
			(end 0.12065 -0.3048)
			(stroke
				(width 0.1)
				(type default)
			)
			(layer "F.Fab")
		)
		(fp_line
			(start -0.12065 -0.2794)
			(end 0.12065 -0.2794)
			(stroke
				(width 0.1)
				(type default)
			)
			(layer "F.Fab")
		)
		(fp_line
			(start 0.120396 0.2794)
			(end -0.12065 0.2794)
			(stroke
				(width 0.1)
				(type default)
			)
			(layer "F.Fab")
		)
		(fp_line
			(start -0.12065 0.2794)
			(end -0.12065 0.3048)
			(stroke
				(width 0.1)
				(type default)
			)
			(layer "F.Fab")
		)
		(fp_line
			(start 0.67945 0.3048)
			(end 0.120396 0.3048)
			(stroke
				(width 0.1)
				(type default)
			)
			(layer "F.Fab")
		)
		(fp_line
			(start 0.120396 0.3048)
			(end 0.120396 0.2794)
			(stroke
				(width 0.1)
				(type default)
			)
			(layer "F.Fab")
		)
		(fp_line
			(start -0.12065 0.3048)
			(end -0.67945 0.3048)
			(stroke
				(width 0.1)
				(type default)
			)
			(layer "F.Fab")
		)
		(fp_line
			(start -0.67945 0.3048)
			(end -0.67945 -0.305054)
			(stroke
				(width 0.1)
				(type default)
			)
			(layer "F.Fab")
		)
		(pad "1" smd circle
			(at -0.40005 0 90)
			(size 0 0)
			(layers "F.Cu" "F.Mask" "F.Paste")
			(net "PVDD18_S5_P0")
		)
		(pad "2" smd circle
			(at 0.40005 0 90)
			(size 0 0)
			(layers "F.Cu" "F.Mask" "F.Paste")
			(net "SPI_CPU0_D0")
		)
	)
)
